(kicad_pcb
	(version 20260206)
	(generator "pcbnew")
	(generator_version "10.0")
	(general
		(thickness 1.6)
		(legacy_teardrops no)
	)
	(paper "A4")
	(title_block
		(title "12092022_DA0F0TMDCD0_F0T_Management_Board_D_brd_V3_OCP.brd")
		(comment 1 "Grand Teton / footprints 202-207 of 1440")
	)
	(layers
		(0 "F.Cu" signal "TOP")
		(4 "In1.Cu" signal "GND")
		(6 "In2.Cu" signal "IN1")
		(8 "In3.Cu" signal "GND1")
		(10 "In4.Cu" signal "IN2")
		(12 "In5.Cu" signal "VCC")
		(14 "In6.Cu" signal "VCC1")
		(16 "In7.Cu" signal "IN3")
		(18 "In8.Cu" signal "GND2")
		(20 "In9.Cu" signal "IN4")
		(22 "In10.Cu" signal "GND3")
		(2 "B.Cu" signal "BOTTOM")
		(9 "F.Adhes" user "F.Adhesive")
		(11 "B.Adhes" user "B.Adhesive")
		(13 "F.Paste" user "Package Geometry/Pastemask Top")
		(15 "B.Paste" user "Package Geometry/Pastemask Bottom")
		(5 "F.SilkS" user "Ref Des/Silkscreen Top")
		(7 "B.SilkS" user "Ref Des/Silkscreen Bottom")
		(1 "F.Mask" user "Board Geometry/Soldermask Top")
		(3 "B.Mask" user "Board Geometry/Soldermask Bottom")
		(17 "Dwgs.User" user "User.Drawings")
		(19 "Cmts.User" user "User.Comments")
		(21 "Eco1.User" user "User.Eco1")
		(23 "Eco2.User" user "User.Eco2")
		(25 "Edge.Cuts" user "Board Geometry/Outline")
		(27 "Margin" user)
		(31 "F.CrtYd" user "Package Geometry/Place Bound Top")
		(29 "B.CrtYd" user "Package Geometry/Place Bound Bottom")
		(35 "F.Fab" user "Ref Des/Assembly Top")
		(33 "B.Fab" user "Ref Des/Assembly Bottom")
	)
	(footprint ""
		(layer "F.Cu")
		(at 78.723744 -35.527488 90)
		(property "Reference" "R336"
			(at 0 0 90)
			(layer "F.SilkS")
			(hide yes)
			(effects
				(font
					(size 1.27 1.27)
				)
			)
		)
		(property "Value" ""
			(at 0 0 90)
			(layer "F.Fab")
			(effects
				(font
					(size 1.27 1.27)
				)
			)
		)
		(duplicate_pad_numbers_are_jumpers no)
		(fp_line
			(start 0.7874 -0.4064)
			(end 0.7874 0.4064)
			(stroke
				(width 0.1524)
				(type default)
			)
			(layer "F.SilkS")
		)
		(fp_line
			(start -0.7874 -0.4064)
			(end 0.7874 -0.4064)
			(stroke
				(width 0.1524)
				(type default)
			)
			(layer "F.SilkS")
		)
		(fp_line
			(start 0.7874 0.4064)
			(end -0.7874 0.4064)
			(stroke
				(width 0.1524)
				(type default)
			)
			(layer "F.SilkS")
		)
		(fp_line
			(start -0.7874 0.4064)
			(end -0.7874 -0.4064)
			(stroke
				(width 0.1524)
				(type default)
			)
			(layer "F.SilkS")
		)
		(fp_line
			(start -0.12065 -0.305054)
			(end -0.12065 -0.2794)
			(stroke
				(width 0.1)
				(type default)
			)
			(layer "F.Fab")
		)
		(fp_line
			(start -0.67945 -0.305054)
			(end -0.12065 -0.305054)
			(stroke
				(width 0.1)
				(type default)
			)
			(layer "F.Fab")
		)
		(fp_line
			(start 0.67945 -0.3048)
			(end 0.67945 0.3048)
			(stroke
				(width 0.1)
				(type default)
			)
			(layer "F.Fab")
		)
		(fp_line
			(start 0.12065 -0.3048)
			(end 0.67945 -0.3048)
			(stroke
				(width 0.1)
				(type default)
			)
			(layer "F.Fab")
		)
		(fp_line
			(start 0.12065 -0.2794)
			(end 0.12065 -0.3048)
			(stroke
				(width 0.1)
				(type default)
			)
			(layer "F.Fab")
		)
		(fp_line
			(start -0.12065 -0.2794)
			(end 0.12065 -0.2794)
			(stroke
				(width 0.1)
				(type default)
			)
			(layer "F.Fab")
		)
		(fp_line
			(start 0.120396 0.2794)
			(end -0.12065 0.2794)
			(stroke
				(width 0.1)
				(type default)
			)
			(layer "F.Fab")
		)
		(fp_line
			(start -0.12065 0.2794)
			(end -0.12065 0.3048)
			(stroke
				(width 0.1)
				(type default)
			)
			(layer "F.Fab")
		)
		(fp_line
			(start 0.67945 0.3048)
			(end 0.120396 0.3048)
			(stroke
				(width 0.1)
				(type default)
			)
			(layer "F.Fab")
		)
		(fp_line
			(start 0.120396 0.3048)
			(end 0.120396 0.2794)
			(stroke
				(width 0.1)
				(type default)
			)
			(layer "F.Fab")
		)
		(fp_line
			(start -0.12065 0.3048)
			(end -0.67945 0.3048)
			(stroke
				(width 0.1)
				(type default)
			)
			(layer "F.Fab")
		)
		(fp_line
			(start -0.67945 0.3048)
			(end -0.67945 -0.305054)
			(stroke
				(width 0.1)
				(type default)
			)
			(layer "F.Fab")
		)
		(pad "1" smd circle
			(at -0.40005 0 90)
			(size 0 0)
			(layers "F.Cu" "F.Mask" "F.Paste")
			(net "GND")
		)
		(pad "2" smd circle
			(at 0.40005 0 90)
			(size 0 0)
			(layers "F.Cu" "F.Mask" "F.Paste")
			(net "M_BMC_DDR4_MA<10>")
		)
	)
	(footprint ""
		(layer "F.Cu")
		(at 55.626 -10.795 90)
		(property "Reference" "R389"
			(at 0 0 90)
			(layer "F.SilkS")
			(hide yes)
			(effects
				(font
					(size 1.27 1.27)
				)
			)
		)
		(property "Value" ""
			(at 0 0 90)
			(layer "F.Fab")
			(effects
				(font
					(size 1.27 1.27)
				)
			)
		)
		(duplicate_pad_numbers_are_jumpers no)
		(fp_line
			(start 0.7874 -0.4064)
			(end 0.7874 0.4064)
			(stroke
				(width 0.1524)
				(type default)
			)
			(layer "F.SilkS")
		)
		(fp_line
			(start -0.7874 -0.4064)
			(end 0.7874 -0.4064)
			(stroke
				(width 0.1524)
				(type default)
			)
			(layer "F.SilkS")
		)
		(fp_line
			(start 0.7874 0.4064)
			(end -0.7874 0.4064)
			(stroke
				(width 0.1524)
				(type default)
			)
			(layer "F.SilkS")
		)
		(fp_line
			(start -0.7874 0.4064)
			(end -0.7874 -0.4064)
			(stroke
				(width 0.1524)
				(type default)
			)
			(layer "F.SilkS")
		)
		(fp_line
			(start -0.12065 -0.305054)
			(end -0.12065 -0.2794)
			(stroke
				(width 0.1)
				(type default)
			)
			(layer "F.Fab")
		)
		(fp_line
			(start -0.67945 -0.305054)
			(end -0.12065 -0.305054)
			(stroke
				(width 0.1)
				(type default)
			)
			(layer "F.Fab")
		)
		(fp_line
			(start 0.67945 -0.3048)
			(end 0.67945 0.3048)
			(stroke
				(width 0.1)
				(type default)
			)
			(layer "F.Fab")
		)
		(fp_line
			(start 0.12065 -0.3048)
			(end 0.67945 -0.3048)
			(stroke
				(width 0.1)
				(type default)
			)
			(layer "F.Fab")
		)
		(fp_line
			(start 0.12065 -0.2794)
			(end 0.12065 -0.3048)
			(stroke
				(width 0.1)
				(type default)
			)
			(layer "F.Fab")
		)
		(fp_line
			(start -0.12065 -0.2794)
			(end 0.12065 -0.2794)
			(stroke
				(width 0.1)
				(type default)
			)
			(layer "F.Fab")
		)
		(fp_line
			(start 0.120396 0.2794)
			(end -0.12065 0.2794)
			(stroke
				(width 0.1)
				(type default)
			)
			(layer "F.Fab")
		)
		(fp_line
			(start -0.12065 0.2794)
			(end -0.12065 0.3048)
			(stroke
				(width 0.1)
				(type default)
			)
			(layer "F.Fab")
		)
		(fp_line
			(start 0.67945 0.3048)
			(end 0.120396 0.3048)
			(stroke
				(width 0.1)
				(type default)
			)
			(layer "F.Fab")
		)
		(fp_line
			(start 0.120396 0.3048)
			(end 0.120396 0.2794)
			(stroke
				(width 0.1)
				(type default)
			)
			(layer "F.Fab")
		)
		(fp_line
			(start -0.12065 0.3048)
			(end -0.67945 0.3048)
			(stroke
				(width 0.1)
				(type default)
			)
			(layer "F.Fab")
		)
		(fp_line
			(start -0.67945 0.3048)
			(end -0.67945 -0.305054)
			(stroke
				(width 0.1)
				(type default)
			)
			(layer "F.Fab")
		)
		(pad "1" smd circle
			(at -0.40005 0 90)
			(size 0 0)
			(layers "F.Cu" "F.Mask" "F.Paste")
			(net "LED_D21_R1")
		)
		(pad "2" smd circle
			(at 0.40005 0 90)
			(size 0 0)
			(layers "F.Cu" "F.Mask" "F.Paste")
			(net "P12V_AUX")
		)
	)
	(footprint ""
		(layer "F.Cu")
		(at 31.75 -26.67 180)
		(property "Reference" "U34"
			(at -1.432052 -0.5842 90)
			(unlocked yes)
			(layer "F.SilkS")
			(effects
				(font
					(size 0.7874 0.5842)
					(thickness 0.1524)
				)
				(justify left)
			)
		)
		(property "Value" ""
			(at 0 0 180)
			(layer "F.Fab")
			(effects
				(font
					(size 1.27 1.27)
				)
			)
		)
		(duplicate_pad_numbers_are_jumpers no)
		(fp_line
			(start 0.791464 1.287526)
			(end 0.791464 -1.287526)
			(stroke
				(width 0.1524)
				(type default)
			)
			(layer "F.SilkS")
		)
		(fp_line
			(start 0.791464 -1.287526)
			(end -0.791464 -1.287526)
			(stroke
				(width 0.1524)
				(type default)
			)
			(layer "F.SilkS")
		)
		(fp_line
			(start -0.791464 1.287526)
			(end 0.791464 1.287526)
			(stroke
				(width 0.1524)
				(type default)
			)
			(layer "F.SilkS")
		)
		(fp_line
			(start -0.791464 -1.287526)
			(end -0.791464 1.287526)
			(stroke
				(width 0.1524)
				(type default)
			)
			(layer "F.SilkS")
		)
		(fp_poly
			(pts
				(xy -1.651 -1.253998) (xy -1.651 -0.745998) (xy -1.143 -0.999998)
			)
			(stroke
				(width 0)
				(type default)
			)
			(fill yes)
			(layer "F.SilkS")
		)
		(fp_line
			(start 0.537464 1.287526)
			(end 0.537464 -1.287526)
			(stroke
				(width 0.1)
				(type default)
			)
			(layer "F.Fab")
		)
		(fp_line
			(start 0.537464 -1.287526)
			(end -0.537464 -1.287526)
			(stroke
				(width 0.1)
				(type default)
			)
			(layer "F.Fab")
		)
		(fp_line
			(start -0.537464 1.287526)
			(end 0.537464 1.287526)
			(stroke
				(width 0.1)
				(type default)
			)
			(layer "F.Fab")
		)
		(fp_line
			(start -0.537464 -1.287526)
			(end -0.537464 1.287526)
			(stroke
				(width 0.1)
				(type default)
			)
			(layer "F.Fab")
		)
		(fp_poly
			(pts
				(xy -1.651 -1.253998) (xy -1.651 -0.745998) (xy -1.143 -0.999998)
			)
			(stroke
				(width 0)
				(type default)
			)
			(fill yes)
			(layer "F.Fab")
		)
		(pad "1" smd rect
			(at -0.387604 -0.999998 270)
			(size 0.254 0.635)
			(layers "F.Cu" "F.Mask" "F.Paste")
			(net "V_BMC_LS_DDC_SCL_R")
		)
		(pad "2" smd rect
			(at -0.387604 -0.499872 270)
			(size 0.254 0.635)
			(layers "F.Cu" "F.Mask" "F.Paste")
			(net "V_BMC_LS_DDC_SDA_R")
		)
		(pad "3" smd rect
			(at -0.350012 0 270)
			(size 0.4572 0.6858)
			(layers "F.Cu" "F.Mask" "F.Paste")
			(net "GND")
		)
		(pad "4" smd rect
			(at -0.387604 0.499872 270)
			(size 0.254 0.635)
			(layers "F.Cu" "F.Mask" "F.Paste")
			(net "V_VGAHS_BUF")
		)
		(pad "5" smd rect
			(at -0.387604 0.999998 270)
			(size 0.254 0.635)
			(layers "F.Cu" "F.Mask" "F.Paste")
			(net "V_VGAVS_BUF")
		)
		(pad "6" smd rect
			(at 0.387604 0.999998 270)
			(size 0.254 0.635)
			(layers "F.Cu" "F.Mask" "F.Paste")
			(net "V_VGAVS_BUF")
		)
		(pad "7" smd rect
			(at 0.387604 0.499872 270)
			(size 0.254 0.635)
			(layers "F.Cu" "F.Mask" "F.Paste")
			(net "V_VGAHS_BUF")
		)
		(pad "8" smd rect
			(at 0.412496 0 270)
			(size 0.4572 0.5842)
			(layers "F.Cu" "F.Mask" "F.Paste")
			(net "GND")
		)
		(pad "9" smd rect
			(at 0.387604 -0.499872 270)
			(size 0.254 0.635)
			(layers "F.Cu" "F.Mask" "F.Paste")
			(net "V_BMC_LS_DDC_SDA_R")
		)
		(pad "10" smd rect
			(at 0.387604 -0.999998 270)
			(size 0.254 0.635)
			(layers "F.Cu" "F.Mask" "F.Paste")
			(net "V_BMC_LS_DDC_SCL_R")
		)
	)
	(footprint ""
		(layer "F.Cu")
		(at 11.070844 -14.812518)
		(property "Reference" "C200"
			(at 0 0 0)
			(layer "F.SilkS")
			(hide yes)
			(effects
				(font
					(size 1.27 1.27)
				)
			)
		)
		(property "Value" ""
			(at 0 0 0)
			(layer "F.Fab")
			(effects
				(font
					(size 1.27 1.27)
				)
			)
		)
		(duplicate_pad_numbers_are_jumpers no)
		(fp_line
			(start -0.7874 -0.4064)
			(end 0.7874 -0.4064)
			(stroke
				(width 0.1524)
				(type default)
			)
			(layer "F.SilkS")
		)
		(fp_line
			(start -0.7874 0.4064)
			(end -0.7874 -0.4064)
			(stroke
				(width 0.1524)
				(type default)
			)
			(layer "F.SilkS")
		)
		(fp_line
			(start 0.7874 -0.4064)
			(end 0.7874 0.4064)
			(stroke
				(width 0.1524)
				(type default)
			)
			(layer "F.SilkS")
		)
		(fp_line
			(start 0.7874 0.4064)
			(end -0.7874 0.4064)
			(stroke
				(width 0.1524)
				(type default)
			)
			(layer "F.SilkS")
		)
		(fp_line
			(start -0.67945 -0.305054)
			(end -0.12065 -0.305054)
			(stroke
				(width 0.1)
				(type default)
			)
			(layer "F.Fab")
		)
		(fp_line
			(start -0.67945 0.3048)
			(end -0.67945 -0.305054)
			(stroke
				(width 0.1)
				(type default)
			)
			(layer "F.Fab")
		)
		(fp_line
			(start -0.12065 -0.305054)
			(end -0.12065 -0.2794)
			(stroke
				(width 0.1)
				(type default)
			)
			(layer "F.Fab")
		)
		(fp_line
			(start -0.12065 -0.2794)
			(end 0.12065 -0.2794)
			(stroke
				(width 0.1)
				(type default)
			)
			(layer "F.Fab")
		)
		(fp_line
			(start -0.12065 0.2794)
			(end -0.12065 0.3048)
			(stroke
				(width 0.1)
				(type default)
			)
			(layer "F.Fab")
		)
		(fp_line
			(start -0.12065 0.3048)
			(end -0.67945 0.3048)
			(stroke
				(width 0.1)
				(type default)
			)
			(layer "F.Fab")
		)
		(fp_line
			(start 0.120396 0.2794)
			(end -0.12065 0.2794)
			(stroke
				(width 0.1)
				(type default)
			)
			(layer "F.Fab")
		)
		(fp_line
			(start 0.120396 0.3048)
			(end 0.120396 0.2794)
			(stroke
				(width 0.1)
				(type default)
			)
			(layer "F.Fab")
		)
		(fp_line
			(start 0.12065 -0.3048)
			(end 0.67945 -0.3048)
			(stroke
				(width 0.1)
				(type default)
			)
			(layer "F.Fab")
		)
		(fp_line
			(start 0.12065 -0.2794)
			(end 0.12065 -0.3048)
			(stroke
				(width 0.1)
				(type default)
			)
			(layer "F.Fab")
		)
		(fp_line
			(start 0.67945 -0.3048)
			(end 0.67945 0.3048)
			(stroke
				(width 0.1)
				(type default)
			)
			(layer "F.Fab")
		)
		(fp_line
			(start 0.67945 0.3048)
			(end 0.120396 0.3048)
			(stroke
				(width 0.1)
				(type default)
			)
			(layer "F.Fab")
		)
		(pad "1" smd circle
			(at -0.40005 0)
			(size 0 0)
			(layers "F.Cu" "F.Mask" "F.Paste")
			(net "P3V3_AUX")
		)
		(pad "2" smd circle
			(at 0.40005 0)
			(size 0 0)
			(layers "F.Cu" "F.Mask" "F.Paste")
			(net "GND")
		)
	)
	(footprint ""
		(layer "F.Cu")
		(at 60.549028 -30.867604 90)
		(property "Reference" "R252"
			(at 0 0 90)
			(layer "F.SilkS")
			(hide yes)
			(effects
				(font
					(size 1.27 1.27)
				)
			)
		)
		(property "Value" ""
			(at 0 0 90)
			(layer "F.Fab")
			(effects
				(font
					(size 1.27 1.27)
				)
			)
		)
		(duplicate_pad_numbers_are_jumpers no)
		(fp_line
			(start 0.7874 -0.4064)
			(end 0.7874 0.4064)
			(stroke
				(width 0.1524)
				(type default)
			)
			(layer "F.SilkS")
		)
		(fp_line
			(start -0.7874 -0.4064)
			(end 0.7874 -0.4064)
			(stroke
				(width 0.1524)
				(type default)
			)
			(layer "F.SilkS")
		)
		(fp_line
			(start 0.7874 0.4064)
			(end -0.7874 0.4064)
			(stroke
				(width 0.1524)
				(type default)
			)
			(layer "F.SilkS")
		)
		(fp_line
			(start -0.7874 0.4064)
			(end -0.7874 -0.4064)
			(stroke
				(width 0.1524)
				(type default)
			)
			(layer "F.SilkS")
		)
		(fp_line
			(start -0.12065 -0.305054)
			(end -0.12065 -0.2794)
			(stroke
				(width 0.1)
				(type default)
			)
			(layer "F.Fab")
		)
		(fp_line
			(start -0.67945 -0.305054)
			(end -0.12065 -0.305054)
			(stroke
				(width 0.1)
				(type default)
			)
			(layer "F.Fab")
		)
		(fp_line
			(start 0.67945 -0.3048)
			(end 0.67945 0.3048)
			(stroke
				(width 0.1)
				(type default)
			)
			(layer "F.Fab")
		)
		(fp_line
			(start 0.12065 -0.3048)
			(end 0.67945 -0.3048)
			(stroke
				(width 0.1)
				(type default)
			)
			(layer "F.Fab")
		)
		(fp_line
			(start 0.12065 -0.2794)
			(end 0.12065 -0.3048)
			(stroke
				(width 0.1)
				(type default)
			)
			(layer "F.Fab")
		)
		(fp_line
			(start -0.12065 -0.2794)
			(end 0.12065 -0.2794)
			(stroke
				(width 0.1)
				(type default)
			)
			(layer "F.Fab")
		)
		(fp_line
			(start 0.120396 0.2794)
			(end -0.12065 0.2794)
			(stroke
				(width 0.1)
				(type default)
			)
			(layer "F.Fab")
		)
		(fp_line
			(start -0.12065 0.2794)
			(end -0.12065 0.3048)
			(stroke
				(width 0.1)
				(type default)
			)
			(layer "F.Fab")
		)
		(fp_line
			(start 0.67945 0.3048)
			(end 0.120396 0.3048)
			(stroke
				(width 0.1)
				(type default)
			)
			(layer "F.Fab")
		)
		(fp_line
			(start 0.120396 0.3048)
			(end 0.120396 0.2794)
			(stroke
				(width 0.1)
				(type default)
			)
			(layer "F.Fab")
		)
		(fp_line
			(start -0.12065 0.3048)
			(end -0.67945 0.3048)
			(stroke
				(width 0.1)
				(type default)
			)
			(layer "F.Fab")
		)
		(fp_line
			(start -0.67945 0.3048)
			(end -0.67945 -0.305054)
			(stroke
				(width 0.1)
				(type default)
			)
			(layer "F.Fab")
		)
		(pad "1" smd circle
			(at -0.40005 0 90)
			(size 0 0)
			(layers "F.Cu" "F.Mask" "F.Paste")
			(net "P3V3_AUX")
		)
		(pad "2" smd circle
			(at 0.40005 0 90)
			(size 0 0)
			(layers "F.Cu" "F.Mask" "F.Paste")
			(net "SMB_BMC_MM5_R_SCL")
		)
	)
	(footprint ""
		(layer "F.Cu")
		(at 75.184 -20.193 180)
		(property "Reference" "R283"
			(at 0 0 180)
			(layer "F.SilkS")
			(hide yes)
			(effects
				(font
					(size 1.27 1.27)
				)
			)
		)
		(property "Value" ""
			(at 0 0 180)
			(layer "F.Fab")
			(effects
				(font
					(size 1.27 1.27)
				)
			)
		)
		(duplicate_pad_numbers_are_jumpers no)
		(fp_line
			(start 0.7874 0.4064)
			(end -0.7874 0.4064)
			(stroke
				(width 0.1524)
				(type default)
			)
			(layer "F.SilkS")
		)
		(fp_line
			(start 0.7874 -0.4064)
			(end 0.7874 0.4064)
			(stroke
				(width 0.1524)
				(type default)
			)
			(layer "F.SilkS")
		)
		(fp_line
			(start -0.7874 0.4064)
			(end -0.7874 -0.4064)
			(stroke
				(width 0.1524)
				(type default)
			)
			(layer "F.SilkS")
		)
		(fp_line
			(start -0.7874 -0.4064)
			(end 0.7874 -0.4064)
			(stroke
				(width 0.1524)
				(type default)
			)
			(layer "F.SilkS")
		)
		(fp_line
			(start 0.67945 0.3048)
			(end 0.120396 0.3048)
			(stroke
				(width 0.1)
				(type default)
			)
			(layer "F.Fab")
		)
		(fp_line
			(start 0.67945 -0.3048)
			(end 0.67945 0.3048)
			(stroke
				(width 0.1)
				(type default)
			)
			(layer "F.Fab")
		)
		(fp_line
			(start 0.12065 -0.2794)
			(end 0.12065 -0.3048)
			(stroke
				(width 0.1)
				(type default)
			)
			(layer "F.Fab")
		)
		(fp_line
			(start 0.12065 -0.3048)
			(end 0.67945 -0.3048)
			(stroke
				(width 0.1)
				(type default)
			)
			(layer "F.Fab")
		)
		(fp_line
			(start 0.120396 0.3048)
			(end 0.120396 0.2794)
			(stroke
				(width 0.1)
				(type default)
			)
			(layer "F.Fab")
		)
		(fp_line
			(start 0.120396 0.2794)
			(end -0.12065 0.2794)
			(stroke
				(width 0.1)
				(type default)
			)
			(layer "F.Fab")
		)
		(fp_line
			(start -0.12065 0.3048)
			(end -0.67945 0.3048)
			(stroke
				(width 0.1)
				(type default)
			)
			(layer "F.Fab")
		)
		(fp_line
			(start -0.12065 0.2794)
			(end -0.12065 0.3048)
			(stroke
				(width 0.1)
				(type default)
			)
			(layer "F.Fab")
		)
		(fp_line
			(start -0.12065 -0.2794)
			(end 0.12065 -0.2794)
			(stroke
				(width 0.1)
				(type default)
			)
			(layer "F.Fab")
		)
		(fp_line
			(start -0.12065 -0.305054)
			(end -0.12065 -0.2794)
			(stroke
				(width 0.1)
				(type default)
			)
			(layer "F.Fab")
		)
		(fp_line
			(start -0.67945 0.3048)
			(end -0.67945 -0.305054)
			(stroke
				(width 0.1)
				(type default)
			)
			(layer "F.Fab")
		)
		(fp_line
			(start -0.67945 -0.305054)
			(end -0.12065 -0.305054)
			(stroke
				(width 0.1)
				(type default)
			)
			(layer "F.Fab")
		)
		(pad "1" smd circle
			(at -0.40005 0 180)
			(size 0 0)
			(layers "F.Cu" "F.Mask" "F.Paste")
			(net "FM_UARTSW_LSB_N")
		)
		(pad "2" smd circle
			(at 0.40005 0 180)
			(size 0 0)
			(layers "F.Cu" "F.Mask" "F.Paste")
			(net "FM_UARTSW_LSB_R1_N")
		)
	)
)
